FILE_TYPE = MACRO_DRAWING;
SET COLOR_WIRE YELLOW;
SET COLOR_PROP ORANGE;
SET COLOR_DOT WHITE;
SET COLOR_ARC YELLOW;
SET COLOR_BODY GREEN;
SET COLOR_NOTE PURPLE;
SET PROP_DISPLAY VALUE;
SET PAGE_NUMBER P262;
FORCEADD UNIVERSAL_GND..1
(-10275 2750);
FORCEPROP 3 LASTPIN (-10275 2800) SIG_NAME GND\g
J 0
(-10265 2810);
DISPLAY 0.659574 (-10265 2810);
PAINT MONO (-10265 2810);
DISPLAY INVISIBLE (-10265 2810);
FORCEPROP 1 LAST HDL_POWER GND
J 1
(-10250 2675);
DISPLAY 0.872340 (-10250 2675);
PAINT GREEN (-10250 2675);
DISPLAY INVISIBLE (-10250 2675);
FORCEPROP 2 LAST CDS_LIB logical_power
J 0
(-10275 2750);
DISPLAY INVISIBLE (-10275 2750);
FORCEPROP 1 LAST PATH I1
J 0
(-10200 2750);
DISPLAY 0.872340 (-10200 2750);
PAINT AQUA (-10200 2750);
DISPLAY INVISIBLE (-10200 2750);
FORCEADD Q_CAP..2
(-9500 3350);
FORCEPROP 1 LAST PART_NUMBER CH4104K1B00
J 1
(-9225 3400);
DISPLAY 0.617021 (-9225 3400);
PAINT BLUE (-9225 3400);
DISPLAY INVISIBLE (-9225 3400);
FORCEPROP 1 LAST TOLERANCE 10%
J 2
(-8850 3400);
DISPLAY 0.617021 (-8850 3400);
PAINT SKYBLUE (-8850 3400);
FORCEPROP 1 LAST PACK_TYPE 0402
J 1
(-9025 3350);
DISPLAY 0.617021 (-9025 3350);
PAINT SKYBLUE (-9025 3350);
FORCEPROP 1 LAST MATERIAL X7R
J 0
(-9050 3400);
DISPLAY 0.617021 (-9050 3400);
PAINT SKYBLUE (-9050 3400);
FORCEPROP 1 LAST VOLTAGE 25V
J 0
(-9200 3350);
DISPLAY 0.617021 (-9200 3350);
PAINT SKYBLUE (-9200 3350);
FORCEPROP 1 LAST VALUE 0.1UF
J 2
(-9225 3350);
DISPLAY 0.617021 (-9225 3350);
PAINT SKYBLUE (-9225 3350);
FORCEPROP 1 LAST LOCATION PC1348
J 1
(-9700 3350);
DISPLAY 0.617021 (-9700 3350);
PAINT AQUA (-9700 3350);
FORCEPROP 1 LASTPIN (-9600 3350) $PN 1
J 0
(-9610 3365);
DISPLAY 0.617021 (-9610 3365);
FORCEPROP 1 LASTPIN (-9400 3350) $PN 2
J 0
(-9415 3365);
DISPLAY 0.617021 (-9415 3365);
FORCEPROP 2 LAST CDS_LIB pure_quanta
J 0
(-9500 3350);
PAINT MONO (-9500 3350);
DISPLAY INVISIBLE (-9500 3350);
FORCEPROP 1 LAST PATH I10
J 0
(-9500 3550);
DISPLAY 0.978723 (-9500 3550);
PAINT WHITE (-9500 3550);
DISPLAY INVISIBLE (-9500 3550);
FORCEPROP 2 LAST $SEC 1
J 0
(-9500 3600);
DISPLAY 0.680851 (-9500 3600);
PAINT MONO (-9500 3600);
DISPLAY INVISIBLE (-9500 3600);
FORCEPROP 2 LAST CDS_SEC 1
J 0
(-9500 3600);
DISPLAY 1.021277 (-9500 3600);
DISPLAY INVISIBLE (-9500 3600);
FORCEADD UNIVERSAL_GND..1
(-9600 3750);
FORCEPROP 3 LASTPIN (-9600 3800) SIG_NAME GND\g
J 0
(-9590 3810);
DISPLAY 0.659574 (-9590 3810);
PAINT MONO (-9590 3810);
DISPLAY INVISIBLE (-9590 3810);
FORCEPROP 1 LAST HDL_POWER GND
J 1
(-9575 3675);
DISPLAY 0.872340 (-9575 3675);
PAINT GREEN (-9575 3675);
DISPLAY INVISIBLE (-9575 3675);
FORCEPROP 2 LAST CDS_LIB logical_power
J 0
(-9600 3750);
PAINT MONO (-9600 3750);
DISPLAY INVISIBLE (-9600 3750);
FORCEPROP 1 LAST PATH I11
J 0
(-9525 3750);
DISPLAY 0.872340 (-9525 3750);
PAINT AQUA (-9525 3750);
DISPLAY INVISIBLE (-9525 3750);
FORCEADD Q_CAP..1
(-9600 4000);
FORCEPROP 1 LAST PART_NUMBER CH5222KEB01
J 0
(-9550 3825);
DISPLAY 0.617021 (-9550 3825);
PAINT BLUE (-9550 3825);
DISPLAY INVISIBLE (-9550 3825);
FORCEPROP 1 LAST VALUE 2.2UF
J 0
(-9550 4075);
DISPLAY 0.617021 (-9550 4075);
PAINT SKYBLUE (-9550 4075);
FORCEPROP 1 LAST PACK_TYPE C0402
J 0
(-9550 3875);
DISPLAY 0.617021 (-9550 3875);
PAINT SKYBLUE (-9550 3875);
FORCEPROP 1 LAST MATERIAL X6S
J 0
(-9550 3925);
DISPLAY 0.617021 (-9550 3925);
PAINT SKYBLUE (-9550 3925);
FORCEPROP 1 LAST TOLERANCE 10%
J 0
(-9550 3975);
DISPLAY 0.617021 (-9550 3975);
PAINT SKYBLUE (-9550 3975);
FORCEPROP 1 LAST VOLTAGE 10V
J 0
(-9550 4025);
DISPLAY 0.617021 (-9550 4025);
PAINT SKYBLUE (-9550 4025);
FORCEPROP 1 LAST LOCATION PC175
J 0
(-9550 4125);
DISPLAY 0.617021 (-9550 4125);
PAINT AQUA (-9550 4125);
FORCEPROP 1 LASTPIN (-9600 4100) $PN 1
J 0
(-9590 4080);
DISPLAY 0.617021 (-9590 4080);
PAINT MONO (-9590 4080);
FORCEPROP 1 LASTPIN (-9600 3900) $PN 2
J 0
(-9590 3880);
DISPLAY 0.617021 (-9590 3880);
PAINT MONO (-9590 3880);
FORCEPROP 2 LAST CDS_LIB pure_quanta
J 0
(-9600 4000);
DISPLAY INVISIBLE (-9600 4000);
FORCEPROP 1 LAST PATH I12
J 0
(-9550 4150);
DISPLAY 0.978723 (-9550 4150);
PAINT WHITE (-9550 4150);
DISPLAY INVISIBLE (-9550 4150);
FORCEPROP 1 LAST LOCATION PC175
J 0
(-9550 4175);
DISPLAY 1.021277 (-9550 4175);
PAINT AQUA (-9550 4175);
DISPLAY INVISIBLE (-9550 4175);
FORCEPROP 0 LAST $SEC 1
J 0
(-9550 4175);
DISPLAY 0.680851 (-9550 4175);
PAINT MONO (-9550 4175);
DISPLAY INVISIBLE (-9550 4175);
FORCEPROP 0 LAST CDS_SEC 1
J 0
(-9550 4175);
DISPLAY 1.021277 (-9550 4175);
DISPLAY INVISIBLE (-9550 4175);
FORCEADD Q_RES..2
(-9075 3950);
FORCEPROP 1 LAST PART_NUMBER CS00002JB13
J 0
(-9035 3825);
DISPLAY 0.510638 (-9035 3825);
DISPLAY INVISIBLE (-9035 3825);
FORCEPROP 1 LAST PACK_TYPE 0402LF
J 0
(-9035 3775);
DISPLAY 0.510638 (-9035 3775);
FORCEPROP 1 LAST WATTAGE 1/16W
J 0
(-9035 3925);
DISPLAY 0.510638 (-9035 3925);
FORCEPROP 1 LAST MATERIAL EMPTY
J 0
(-9035 3875);
DISPLAY 0.510638 (-9035 3875);
PAINT RED (-9035 3875);
FORCEPROP 1 LAST TOLERANCE 5%
J 0
(-9030 3975);
DISPLAY 0.510638 (-9030 3975);
FORCEPROP 1 LAST VALUE 0
J 0
(-9030 4025);
DISPLAY 0.510638 (-9030 4025);
FORCEPROP 1 LAST LOCATION PR4227
J 0
(-9030 4075);
DISPLAY 0.510638 (-9030 4075);
FORCEPROP 1 LASTPIN (-9075 4050) $PN 1
J 0
(-9070 4012);
DISPLAY 0.787234 (-9070 4012);
PAINT MONO (-9070 4012);
FORCEPROP 1 LASTPIN (-9075 3850) $PN 2
J 0
(-9070 3860);
DISPLAY 0.787234 (-9070 3860);
PAINT MONO (-9070 3860);
FORCEPROP 2 LAST CDS_LIB pure_quanta
J 0
(-9075 3950);
DISPLAY INVISIBLE (-9075 3950);
FORCEPROP 1 LAST PATH I13
J 0
(-9025 4125);
DISPLAY 0.978723 (-9025 4125);
PAINT WHITE (-9025 4125);
DISPLAY INVISIBLE (-9025 4125);
FORCEPROP 0 LAST $SEC 1
J 0
(-9025 4100);
DISPLAY 0.680851 (-9025 4100);
PAINT MONO (-9025 4100);
DISPLAY INVISIBLE (-9025 4100);
FORCEPROP 0 LAST CDS_SEC 1
J 0
(-9025 4100);
DISPLAY 1.021277 (-9025 4100);
DISPLAY INVISIBLE (-9025 4100);
FORCEADD RAA2213404GNPHB0..1
(-8100 3575);
FORCEPROP 1 LAST PART_NUMBER AL221340002
J 0
(-8375 4325);
DISPLAY 0.617021 (-8375 4325);
PAINT BLUE (-8375 4325);
DISPLAY INVISIBLE (-8375 4325);
FORCEPROP 2 LAST PART_TYPE SMLF
J 0
(-8375 4500);
DISPLAY 0.808511 (-8375 4500);
FORCEPROP 2 LAST VALUE RAA2213404GNP#HB0
J 0
(-8375 4450);
DISPLAY 0.617021 (-8375 4450);
PAINT SKYBLUE (-8375 4450);
FORCEPROP 1 LAST MATERIAL IC
J 0
(-8370 4257);
DISPLAY 0.617021 (-8370 4257);
PAINT SKYBLUE (-8370 4257);
FORCEPROP 1 LAST LOCATION PU42
J 0
(-8375 4400);
DISPLAY 0.617021 (-8375 4400);
PAINT AQUA (-8375 4400);
FORCEPROP 0 LASTPIN (-7675 3900) $PN 20
J 0
(-7665 3910);
DISPLAY 0.617021 (-7665 3910);
PAINT MONO (-7665 3910);
FORCEPROP 0 LASTPIN (-7675 3050) $PN 2
J 0
(-7665 3060);
DISPLAY 0.617021 (-7665 3060);
PAINT MONO (-7665 3060);
FORCEPROP 0 LASTPIN (-8525 3300) $PN 5
J 2
(-8535 3310);
DISPLAY 0.617021 (-8535 3310);
PAINT MONO (-8535 3310);
FORCEPROP 0 LASTPIN (-8525 3250) $PN 27
J 2
(-8535 3260);
DISPLAY 0.617021 (-8535 3260);
PAINT MONO (-8535 3260);
FORCEPROP 0 LASTPIN (-7675 2950) $PN 6_7-13_15-29
J 0
(-6340 2960);
DISPLAY 0.617021 (-6340 2960);
PAINT MONO (-6340 2960);
FORCEPROP 0 LASTPIN (-7675 3100) $PN 23
J 0
(-7665 3110);
DISPLAY 0.617021 (-7665 3110);
PAINT MONO (-7665 3110);
FORCEPROP 0 LASTPIN (-7675 3000) $PN 26
J 0
(-7665 3010);
DISPLAY 0.617021 (-7665 3010);
PAINT MONO (-7665 3010);
FORCEPROP 0 LASTPIN (-8525 3550) $PN 25
J 2
(-8535 3560);
DISPLAY 0.617021 (-8535 3560);
PAINT MONO (-8535 3560);
FORCEPROP 0 LASTPIN (-7675 3250) $PN 3
J 0
(-7665 3260);
DISPLAY 0.617021 (-7665 3260);
PAINT MONO (-7665 3260);
FORCEPROP 0 LASTPIN (-8525 3700) $PN 22
J 2
(-8535 3710);
DISPLAY 0.617021 (-8535 3710);
PAINT MONO (-8535 3710);
FORCEPROP 0 LASTPIN (-7675 3650) $PN 19
J 0
(-7665 3660);
DISPLAY 0.617021 (-7665 3660);
PAINT MONO (-7665 3660);
FORCEPROP 0 LASTPIN (-8525 2950) $PN 21
J 2
(-8535 2960);
DISPLAY 0.617021 (-8535 2960);
PAINT MONO (-8535 2960);
FORCEPROP 0 LASTPIN (-8525 3450) $PN 24
J 2
(-8535 3460);
DISPLAY 0.617021 (-8535 3460);
PAINT MONO (-8535 3460);
FORCEPROP 0 LASTPIN (-7675 3550) $PN 8_12
J 0
(-7665 3560);
DISPLAY 0.617021 (-7665 3560);
PAINT MONO (-7665 3560);
FORCEPROP 0 LASTPIN (-8525 3050) $PN 1
J 2
(-8535 3060);
DISPLAY 0.617021 (-8535 3060);
PAINT MONO (-8535 3060);
FORCEPROP 0 LASTPIN (-8525 4200) $PN 4
J 2
(-8535 4210);
DISPLAY 0.617021 (-8535 4210);
PAINT MONO (-8535 4210);
FORCEPROP 0 LASTPIN (-7675 4200) $PN 16_18-28
J 0
(-7665 4210);
DISPLAY 0.617021 (-7665 4210);
PAINT MONO (-7665 4210);
FORCEPROP 2 LAST CDS_LIB pure_quanta
J 0
(-8100 3575);
DISPLAY INVISIBLE (-8100 3575);
FORCEPROP 1 LAST CDS_LMAN_SYM_OUTLINE -275,675,275,-675
J 0
(-8100 3575);
DISPLAY 0.468085 (-8100 3575);
PAINT GREEN (-8100 3575);
DISPLAY INVISIBLE (-8100 3575);
FORCEPROP 1 LAST NEEDS_NO_SIZE TRUE
J 0
(-8100 3575);
DISPLAY 0.723404 (-8100 3575);
PAINT GREEN (-8100 3575);
DISPLAY INVISIBLE (-8100 3575);
FORCEPROP 1 LAST PATH I14
J 0
(-8100 3575);
DISPLAY 0.723404 (-8100 3575);
PAINT GREEN (-8100 3575);
DISPLAY INVISIBLE (-8100 3575);
FORCEPROP 0 LAST $SEC 1
J 0
(-8375 4600);
DISPLAY 0.680851 (-8375 4600);
PAINT MONO (-8375 4600);
DISPLAY INVISIBLE (-8375 4600);
FORCEPROP 0 LAST CDS_SEC 1
J 0
(-8375 4600);
DISPLAY 1.021277 (-8375 4600);
DISPLAY INVISIBLE (-8375 4600);
FORCEADD Q_RES..1
(-6725 3050);
FORCEPROP 1 LAST PART_NUMBER CS00002JB13
J 0
(-6825 3100);
DISPLAY 0.617021 (-6825 3100);
PAINT BLUE (-6825 3100);
DISPLAY INVISIBLE (-6825 3100);
FORCEPROP 1 LAST WATTAGE 1/16W
J 2
(-6475 3125);
DISPLAY 0.617021 (-6475 3125);
PAINT SKYBLUE (-6475 3125);
FORCEPROP 1 LAST MATERIAL EMPTY
J 0
(-6825 3150);
DISPLAY 0.617021 (-6825 3150);
PAINT RED (-6825 3150);
FORCEPROP 1 LAST PACK_TYPE 0402LF
J 0
(-6825 3125);
DISPLAY 0.617021 (-6825 3125);
PAINT SKYBLUE (-6825 3125);
FORCEPROP 1 LAST VALUE 0
J 2
(-6600 3050);
DISPLAY 0.617021 (-6600 3050);
PAINT SKYBLUE (-6600 3050);
FORCEPROP 1 LAST TOLERANCE 5%
J 0
(-6575 3050);
DISPLAY 0.617021 (-6575 3050);
PAINT SKYBLUE (-6575 3050);
FORCEPROP 1 LAST LOCATION PR4228
J 0
(-6925 3050);
DISPLAY 0.617021 (-6925 3050);
PAINT AQUA (-6925 3050);
FORCEPROP 1 LASTPIN (-6825 3050) $PN 1
J 0
(-6813 3062);
DISPLAY 0.787234 (-6813 3062);
PAINT MONO (-6813 3062);
FORCEPROP 1 LASTPIN (-6625 3050) $PN 2
J 0
(-6663 3062);
DISPLAY 0.787234 (-6663 3062);
PAINT MONO (-6663 3062);
FORCEPROP 2 LAST CDS_LIB pure_quanta
J 0
(-6725 3050);
DISPLAY INVISIBLE (-6725 3050);
FORCEPROP 1 LAST PATH I15
J 0
(-6775 3200);
DISPLAY 0.978723 (-6775 3200);
PAINT WHITE (-6775 3200);
DISPLAY INVISIBLE (-6775 3200);
FORCEPROP 0 LAST $SEC 1
J 0
(-6825 3200);
DISPLAY 0.680851 (-6825 3200);
PAINT MONO (-6825 3200);
DISPLAY INVISIBLE (-6825 3200);
FORCEPROP 0 LAST CDS_SEC 1
J 0
(-6825 3200);
DISPLAY 1.021277 (-6825 3200);
DISPLAY INVISIBLE (-6825 3200);
FORCEADD Q_RES..1
(-6525 3250);
FORCEPROP 1 LAST PART_NUMBER CS00002JB13
J 0
(-6625 3300);
DISPLAY 0.617021 (-6625 3300);
PAINT BLUE (-6625 3300);
DISPLAY INVISIBLE (-6625 3300);
FORCEPROP 1 LAST WATTAGE 1/16W
J 2
(-6275 3325);
DISPLAY 0.617021 (-6275 3325);
PAINT SKYBLUE (-6275 3325);
FORCEPROP 1 LAST TOLERANCE 5%
J 0
(-6375 3250);
DISPLAY 0.617021 (-6375 3250);
PAINT SKYBLUE (-6375 3250);
FORCEPROP 1 LAST VALUE 0
J 2
(-6400 3250);
DISPLAY 0.617021 (-6400 3250);
PAINT SKYBLUE (-6400 3250);
FORCEPROP 1 LAST MATERIAL CHIP
J 0
(-6625 3350);
DISPLAY 0.617021 (-6625 3350);
PAINT SKYBLUE (-6625 3350);
FORCEPROP 1 LAST PACK_TYPE 0402LF
J 0
(-6625 3325);
DISPLAY 0.617021 (-6625 3325);
PAINT SKYBLUE (-6625 3325);
FORCEPROP 1 LAST LOCATION PR1779
J 0
(-6775 3250);
DISPLAY 0.617021 (-6775 3250);
PAINT AQUA (-6775 3250);
FORCEPROP 1 LASTPIN (-6625 3250) $PN 1
J 0
(-6613 3262);
DISPLAY 0.617021 (-6613 3262);
FORCEPROP 1 LASTPIN (-6425 3250) $PN 2
J 0
(-6463 3262);
DISPLAY 0.617021 (-6463 3262);
FORCEPROP 2 LAST CDS_LIB pure_quanta
J 0
(-6525 3250);
PAINT MONO (-6525 3250);
DISPLAY INVISIBLE (-6525 3250);
FORCEPROP 1 LAST PATH I16
J 0
(-6575 3400);
DISPLAY 0.978723 (-6575 3400);
PAINT WHITE (-6575 3400);
DISPLAY INVISIBLE (-6575 3400);
FORCEPROP 2 LAST $SEC 1
J 0
(-6575 3450);
DISPLAY 0.680851 (-6575 3450);
PAINT MONO (-6575 3450);
DISPLAY INVISIBLE (-6575 3450);
FORCEPROP 2 LAST CDS_SEC 1
J 0
(-6575 3450);
DISPLAY 1.021277 (-6575 3450);
DISPLAY INVISIBLE (-6575 3450);
FORCEADD Q_RES..1
(-6750 4000);
FORCEPROP 1 LAST PART_NUMBER CS-3302FB01
J 0
(-7000 3875);
DISPLAY 0.617021 (-7000 3875);
PAINT BLUE (-7000 3875);
DISPLAY INVISIBLE (-7000 3875);
FORCEPROP 1 LAST PACK_TYPE 0402LF
J 0
(-7000 3925);
DISPLAY 0.617021 (-7000 3925);
PAINT SKYBLUE (-7000 3925);
FORCEPROP 1 LAST MATERIAL CHIP
J 0
(-7000 3975);
DISPLAY 0.617021 (-7000 3975);
PAINT SKYBLUE (-7000 3975);
FORCEPROP 1 LAST WATTAGE 1/16W
J 2
(-6625 3925);
DISPLAY 0.617021 (-6625 3925);
PAINT SKYBLUE (-6625 3925);
FORCEPROP 1 LAST TOLERANCE 1%
J 0
(-6500 4000);
DISPLAY 0.617021 (-6500 4000);
PAINT SKYBLUE (-6500 4000);
FORCEPROP 1 LAST VALUE 3.3
J 2
(-6525 4000);
DISPLAY 0.617021 (-6525 4000);
PAINT SKYBLUE (-6525 4000);
FORCEPROP 1 LAST LOCATION PR1778
J 0
(-7000 4000);
DISPLAY 0.617021 (-7000 4000);
PAINT AQUA (-7000 4000);
FORCEPROP 1 LASTPIN (-6850 4000) $PN 1
J 0
(-6838 4012);
DISPLAY 0.617021 (-6838 4012);
FORCEPROP 1 LASTPIN (-6650 4000) $PN 2
J 0
(-6688 4012);
DISPLAY 0.617021 (-6688 4012);
FORCEPROP 2 LAST CDS_LIB pure_quanta
J 0
(-6750 4000);
PAINT MONO (-6750 4000);
DISPLAY INVISIBLE (-6750 4000);
FORCEPROP 1 LAST PATH I17
J 0
(-6800 4150);
DISPLAY 0.978723 (-6800 4150);
PAINT WHITE (-6800 4150);
DISPLAY INVISIBLE (-6800 4150);
FORCEPROP 2 LAST $SEC 1
J 0
(-6800 4200);
DISPLAY 0.680851 (-6800 4200);
PAINT MONO (-6800 4200);
DISPLAY INVISIBLE (-6800 4200);
FORCEPROP 2 LAST CDS_SEC 1
J 0
(-6800 4200);
DISPLAY 1.021277 (-6800 4200);
DISPLAY INVISIBLE (-6800 4200);
FORCEADD UNIVERSAL_GND..1
(-6100 2825);
FORCEPROP 3 LASTPIN (-6100 2875) SIG_NAME GND\g
J 0
(-6090 2885);
DISPLAY 0.659574 (-6090 2885);
PAINT MONO (-6090 2885);
DISPLAY INVISIBLE (-6090 2885);
FORCEPROP 1 LAST HDL_POWER GND
J 1
(-6075 2750);
DISPLAY 0.872340 (-6075 2750);
PAINT GREEN (-6075 2750);
DISPLAY INVISIBLE (-6075 2750);
FORCEPROP 2 LAST CDS_LIB logical_power
J 0
(-6100 2825);
PAINT MONO (-6100 2825);
DISPLAY INVISIBLE (-6100 2825);
FORCEPROP 1 LAST PATH I18
J 0
(-6025 2825);
DISPLAY 0.872340 (-6025 2825);
PAINT AQUA (-6025 2825);
DISPLAY INVISIBLE (-6025 2825);
FORCEADD VCC15..1
(-6100 3400);
FORCEPROP 3 LASTPIN (-6100 3350) SIG_NAME PVCCFA_EHV_CPU0_VDD1\g
J 0
(-6090 3360);
DISPLAY 0.659574 (-6090 3360);
PAINT MONO (-6090 3360);
DISPLAY INVISIBLE (-6090 3360);
FORCEPROP 1 LAST HDL_POWER PVCCFA_EHV_CPU0_VDD1
J 1
(-6050 3450);
DISPLAY 0.617021 (-6050 3450);
PAINT GREEN (-6050 3450);
FORCEPROP 2 LAST CDS_LIB logical_power
J 0
(-6100 3400);
PAINT MONO (-6100 3400);
DISPLAY INVISIBLE (-6100 3400);
FORCEPROP 1 LAST PATH I19
J 0
(-6050 3425);
DISPLAY 0.872340 (-6050 3425);
PAINT AQUA (-6050 3425);
DISPLAY INVISIBLE (-6050 3425);
FORCEADD Q_RES..2
R 2
(-10275 2975);
FORCEPROP 1 LAST PART_NUMBER CS28872FB01
J 2
(-10315 2850);
DISPLAY 0.617021 (-10315 2850);
PAINT BLUE (-10315 2850);
DISPLAY INVISIBLE (-10315 2850);
FORCEPROP 1 LAST PACK_TYPE 0402LF
J 2
(-10315 2800);
DISPLAY 0.617021 (-10315 2800);
PAINT SKYBLUE (-10315 2800);
FORCEPROP 1 LAST VALUE 8.87K
J 2
(-10320 3050);
DISPLAY 0.617021 (-10320 3050);
PAINT SKYBLUE (-10320 3050);
FORCEPROP 1 LAST TOLERANCE 1%
J 2
(-10320 3000);
DISPLAY 0.617021 (-10320 3000);
PAINT SKYBLUE (-10320 3000);
FORCEPROP 1 LAST MATERIAL EMPTY
J 2
(-10315 2900);
DISPLAY 0.617021 (-10315 2900);
PAINT RED (-10315 2900);
FORCEPROP 1 LAST WATTAGE 1/16W
J 2
(-10315 2950);
DISPLAY 0.617021 (-10315 2950);
PAINT SKYBLUE (-10315 2950);
FORCEPROP 1 LAST LOCATION PR1709
J 2
(-10320 3100);
DISPLAY 0.617021 (-10320 3100);
PAINT AQUA (-10320 3100);
FORCEPROP 1 LASTPIN (-10275 3075) $PN 1
J 2
(-10280 3037);
DISPLAY 0.617021 (-10280 3037);
PAINT MONO (-10280 3037);
FORCEPROP 1 LASTPIN (-10275 2875) $PN 2
J 2
(-10280 2885);
DISPLAY 0.617021 (-10280 2885);
PAINT MONO (-10280 2885);
FORCEPROP 2 LAST CDS_LIB pure_quanta
J 2
(-10275 2975);
DISPLAY INVISIBLE (-10275 2975);
FORCEPROP 1 LAST PATH I2
J 2
(-10325 3150);
DISPLAY 0.978723 (-10325 3150);
PAINT WHITE (-10325 3150);
DISPLAY INVISIBLE (-10325 3150);
FORCEPROP 0 LAST $SEC 1
J 0
(-10300 3125);
DISPLAY 0.680851 (-10300 3125);
PAINT MONO (-10300 3125);
DISPLAY INVISIBLE (-10300 3125);
FORCEPROP 0 LAST CDS_SEC 1
J 0
(-10300 3125);
DISPLAY 1.021277 (-10300 3125);
DISPLAY INVISIBLE (-10300 3125);
FORCEADD Q_CAP..1
R 2
(-5950 3825);
FORCEPROP 1 LAST PART_NUMBER CH4106K1B01
J 2
(-6000 3700);
DISPLAY 0.617021 (-6000 3700);
PAINT BLUE (-6000 3700);
DISPLAY INVISIBLE (-6000 3700);
FORCEPROP 1 LAST MATERIAL X7R
J 2
(-6000 3750);
DISPLAY 0.617021 (-6000 3750);
PAINT SKYBLUE (-6000 3750);
FORCEPROP 1 LAST PACK_TYPE C0402
J 2
(-6000 3650);
DISPLAY 0.617021 (-6000 3650);
PAINT SKYBLUE (-6000 3650);
FORCEPROP 1 LAST VALUE 100NF
J 2
(-6000 3900);
DISPLAY 0.617021 (-6000 3900);
PAINT SKYBLUE (-6000 3900);
FORCEPROP 1 LAST VOLTAGE 50V
J 2
(-6000 3850);
DISPLAY 0.617021 (-6000 3850);
PAINT SKYBLUE (-6000 3850);
FORCEPROP 1 LAST TOLERANCE 10%
J 2
(-6000 3800);
DISPLAY 0.617021 (-6000 3800);
PAINT SKYBLUE (-6000 3800);
FORCEPROP 1 LAST LOCATION PC178
J 2
(-6000 3950);
DISPLAY 0.617021 (-6000 3950);
PAINT AQUA (-6000 3950);
FORCEPROP 1 LASTPIN (-5950 3925) $PN 1
J 2
(-5960 3905);
DISPLAY 0.617021 (-5960 3905);
FORCEPROP 1 LASTPIN (-5950 3725) $PN 2
J 2
(-5960 3705);
DISPLAY 0.617021 (-5960 3705);
FORCEPROP 2 LAST CDS_LIB pure_quanta
J 2
(-5950 3825);
PAINT MONO (-5950 3825);
DISPLAY INVISIBLE (-5950 3825);
FORCEPROP 1 LAST PATH I20
J 2
(-6000 3975);
DISPLAY 0.978723 (-6000 3975);
PAINT WHITE (-6000 3975);
DISPLAY INVISIBLE (-6000 3975);
FORCEPROP 2 LAST $SEC 1
J 0
(-6000 4025);
DISPLAY 0.680851 (-6000 4025);
PAINT MONO (-6000 4025);
DISPLAY INVISIBLE (-6000 4025);
FORCEPROP 2 LAST CDS_SEC 1
J 0
(-6000 4025);
DISPLAY 1.021277 (-6000 4025);
DISPLAY INVISIBLE (-6000 4025);
FORCEADD Q_RES..2
(-9600 4400);
FORCEPROP 1 LAST PART_NUMBER CS-2202FB01
J 0
(-9560 4275);
DISPLAY 0.617021 (-9560 4275);
PAINT BLUE (-9560 4275);
DISPLAY INVISIBLE (-9560 4275);
FORCEPROP 1 LAST WATTAGE 1/16W
J 0
(-9560 4375);
DISPLAY 0.617021 (-9560 4375);
PAINT SKYBLUE (-9560 4375);
FORCEPROP 1 LAST MATERIAL CHIP
J 0
(-9560 4325);
DISPLAY 0.617021 (-9560 4325);
PAINT SKYBLUE (-9560 4325);
FORCEPROP 1 LAST PACK_TYPE 0402LF
J 0
(-9560 4225);
DISPLAY 0.617021 (-9560 4225);
PAINT SKYBLUE (-9560 4225);
FORCEPROP 1 LAST VALUE 2.2
J 0
(-9555 4475);
DISPLAY 0.617021 (-9555 4475);
PAINT SKYBLUE (-9555 4475);
FORCEPROP 1 LAST TOLERANCE 1%
J 0
(-9555 4425);
DISPLAY 0.617021 (-9555 4425);
PAINT SKYBLUE (-9555 4425);
FORCEPROP 1 LAST LOCATION PR97
J 0
(-9555 4525);
DISPLAY 0.617021 (-9555 4525);
PAINT AQUA (-9555 4525);
FORCEPROP 1 LASTPIN (-9600 4500) $PN 1
J 0
(-9595 4462);
DISPLAY 0.617021 (-9595 4462);
PAINT MONO (-9595 4462);
FORCEPROP 1 LASTPIN (-9600 4300) $PN 2
J 0
(-9595 4310);
DISPLAY 0.617021 (-9595 4310);
PAINT MONO (-9595 4310);
FORCEPROP 2 LAST CDS_LIB pure_quanta
J 0
(-9600 4400);
DISPLAY INVISIBLE (-9600 4400);
FORCEPROP 1 LAST PATH I21
J 0
(-9550 4575);
DISPLAY 0.978723 (-9550 4575);
PAINT WHITE (-9550 4575);
DISPLAY INVISIBLE (-9550 4575);
FORCEPROP 1 LAST LOCATION PR97
J 0
(-9550 4575);
DISPLAY 1.021277 (-9550 4575);
PAINT AQUA (-9550 4575);
DISPLAY INVISIBLE (-9550 4575);
FORCEPROP 0 LAST $SEC 1
J 0
(-9550 4575);
DISPLAY 0.680851 (-9550 4575);
PAINT MONO (-9550 4575);
DISPLAY INVISIBLE (-9550 4575);
FORCEPROP 0 LAST CDS_SEC 1
J 0
(-9550 4575);
DISPLAY 1.021277 (-9550 4575);
DISPLAY INVISIBLE (-9550 4575);
FORCEADD Q_RES..2
(-9225 5025);
FORCEPROP 1 LAST PART_NUMBER CS00002JB13
J 0
(-9185 4900);
DISPLAY 0.617021 (-9185 4900);
PAINT BLUE (-9185 4900);
DISPLAY INVISIBLE (-9185 4900);
FORCEPROP 1 LAST PACK_TYPE 0402LF
J 0
(-9185 4850);
DISPLAY 0.617021 (-9185 4850);
PAINT SKYBLUE (-9185 4850);
FORCEPROP 1 LAST VALUE 0
J 0
(-9180 5100);
DISPLAY 0.617021 (-9180 5100);
PAINT SKYBLUE (-9180 5100);
FORCEPROP 1 LAST TOLERANCE 5%
J 0
(-9180 5050);
DISPLAY 0.617021 (-9180 5050);
PAINT SKYBLUE (-9180 5050);
FORCEPROP 1 LAST MATERIAL EMPTY
J 0
(-9185 4950);
DISPLAY 0.617021 (-9185 4950);
PAINT RED (-9185 4950);
FORCEPROP 1 LAST WATTAGE 1/16W
J 0
(-9185 5000);
DISPLAY 0.617021 (-9185 5000);
PAINT SKYBLUE (-9185 5000);
FORCEPROP 1 LAST LOCATION PR443
J 0
(-9180 5150);
DISPLAY 0.617021 (-9180 5150);
PAINT AQUA (-9180 5150);
FORCEPROP 2 LAST CDS_LIB pure_quanta
J 0
(-9225 5025);
DISPLAY INVISIBLE (-9225 5025);
FORCEPROP 1 LAST PATH I22
J 0
(-9175 5200);
DISPLAY 0.978723 (-9175 5200);
PAINT WHITE (-9175 5200);
DISPLAY INVISIBLE (-9175 5200);
FORCEPROP 0 LAST $SEC 1
J 0
(-9175 5200);
DISPLAY INVISIBLE (-9175 5200);
FORCEPROP 0 LAST CDS_SEC 1
J 0
(-9175 5200);
DISPLAY INVISIBLE (-9175 5200);
FORCEPROP 1 LASTPIN (-9225 5125) $PN 1
J 0
(-9220 5087);
DISPLAY 0.787234 (-9220 5087);
PAINT MONO (-9220 5087);
DISPLAY INVISIBLE (-9220 5087);
FORCEPROP 1 LASTPIN (-9225 4925) $PN 2
J 0
(-9220 4935);
DISPLAY 0.787234 (-9220 4935);
PAINT MONO (-9220 4935);
DISPLAY INVISIBLE (-9220 4935);
FORCEADD VCC15..1
(-9225 5250);
FORCEPROP 3 LASTPIN (-9225 5200) SIG_NAME P3V3\g
J 0
(-9215 5210);
DISPLAY 0.659574 (-9215 5210);
PAINT MONO (-9215 5210);
DISPLAY INVISIBLE (-9215 5210);
FORCEPROP 1 LAST HDL_POWER P3V3
J 1
(-9225 5300);
DISPLAY 0.617021 (-9225 5300);
PAINT GREEN (-9225 5300);
FORCEPROP 2 LAST CDS_LIB logical_power
J 0
(-9225 5250);
DISPLAY INVISIBLE (-9225 5250);
FORCEPROP 1 LAST PATH I23
J 0
(-9175 5275);
DISPLAY 0.872340 (-9175 5275);
PAINT AQUA (-9175 5275);
DISPLAY INVISIBLE (-9175 5275);
FORCEADD Q_CAP..1
(-7275 4450);
FORCEPROP 1 LAST PART_NUMBER TMP_QCH2336K1B12
J 0
(-7225 4250);
DISPLAY 0.617021 (-7225 4250);
PAINT BLUE (-7225 4250);
DISPLAY INVISIBLE (-7225 4250);
FORCEPROP 1 LAST TOLERANCE 10%
J 0
(-7225 4450);
DISPLAY 0.617021 (-7225 4450);
PAINT SKYBLUE (-7225 4450);
FORCEPROP 1 LAST VOLTAGE 50V
J 0
(-7225 4500);
DISPLAY 0.617021 (-7225 4500);
PAINT SKYBLUE (-7225 4500);
FORCEPROP 1 LAST VALUE 3300PF
J 0
(-7225 4550);
DISPLAY 0.617021 (-7225 4550);
PAINT SKYBLUE (-7225 4550);
FORCEPROP 1 LAST PACK_TYPE 0402
J 0
(-7225 4350);
DISPLAY 0.617021 (-7225 4350);
PAINT SKYBLUE (-7225 4350);
FORCEPROP 1 LAST MATERIAL X7R
J 0
(-7225 4400);
DISPLAY 0.617021 (-7225 4400);
PAINT SKYBLUE (-7225 4400);
FORCEPROP 1 LAST LOCATION PC176
J 0
(-7225 4600);
DISPLAY 0.617021 (-7225 4600);
PAINT AQUA (-7225 4600);
FORCEPROP 1 LASTPIN (-7275 4550) $PN 1
J 0
(-7265 4530);
DISPLAY 0.617021 (-7265 4530);
PAINT MONO (-7265 4530);
FORCEPROP 1 LASTPIN (-7275 4350) $PN 2
J 0
(-7265 4330);
DISPLAY 0.617021 (-7265 4330);
PAINT MONO (-7265 4330);
FORCEPROP 2 LAST CDS_LIB pure_quanta
J 0
(-7275 4450);
DISPLAY INVISIBLE (-7275 4450);
FORCEPROP 1 LAST PATH I24
J 0
(-7225 4600);
DISPLAY 0.978723 (-7225 4600);
PAINT WHITE (-7225 4600);
DISPLAY INVISIBLE (-7225 4600);
FORCEPROP 1 LAST LOCATION PC176
J 0
(-7225 4650);
DISPLAY 1.021277 (-7225 4650);
PAINT AQUA (-7225 4650);
DISPLAY INVISIBLE (-7225 4650);
FORCEPROP 0 LAST $SEC 1
J 0
(-7225 4650);
DISPLAY 0.680851 (-7225 4650);
PAINT MONO (-7225 4650);
DISPLAY INVISIBLE (-7225 4650);
FORCEPROP 0 LAST CDS_SEC 1
J 0
(-7225 4650);
DISPLAY 1.021277 (-7225 4650);
DISPLAY INVISIBLE (-7225 4650);
FORCEADD Q_CAP..1
(-6875 4450);
FORCEPROP 1 LAST PART_NUMBER CH5103KEB01
J 0
(-6825 4300);
DISPLAY 0.617021 (-6825 4300);
PAINT BLUE (-6825 4300);
DISPLAY INVISIBLE (-6825 4300);
FORCEPROP 1 LAST VOLTAGE 16V
J 0
(-6825 4500);
DISPLAY 0.617021 (-6825 4500);
PAINT SKYBLUE (-6825 4500);
FORCEPROP 1 LAST PACK_TYPE C0402
J 0
(-6825 4350);
DISPLAY 0.617021 (-6825 4350);
PAINT SKYBLUE (-6825 4350);
FORCEPROP 1 LAST VALUE 1UF
J 0
(-6825 4550);
DISPLAY 0.617021 (-6825 4550);
PAINT SKYBLUE (-6825 4550);
FORCEPROP 1 LAST MATERIAL X6S
J 0
(-6825 4400);
DISPLAY 0.617021 (-6825 4400);
PAINT SKYBLUE (-6825 4400);
FORCEPROP 1 LAST TOLERANCE 10%
J 0
(-6825 4450);
DISPLAY 0.617021 (-6825 4450);
PAINT SKYBLUE (-6825 4450);
FORCEPROP 1 LAST LOCATION PC177
J 0
(-6825 4600);
DISPLAY 0.617021 (-6825 4600);
PAINT AQUA (-6825 4600);
FORCEPROP 1 LASTPIN (-6875 4550) $PN 1
J 0
(-6865 4530);
DISPLAY 0.617021 (-6865 4530);
PAINT MONO (-6865 4530);
FORCEPROP 1 LASTPIN (-6875 4350) $PN 2
J 0
(-6865 4330);
DISPLAY 0.617021 (-6865 4330);
PAINT MONO (-6865 4330);
FORCEPROP 2 LAST CDS_LIB pure_quanta
J 0
(-6875 4450);
DISPLAY INVISIBLE (-6875 4450);
FORCEPROP 1 LAST PATH I25
J 0
(-6825 4600);
DISPLAY 0.978723 (-6825 4600);
PAINT WHITE (-6825 4600);
DISPLAY INVISIBLE (-6825 4600);
FORCEPROP 1 LAST LOCATION PC177
J 0
(-6825 4650);
DISPLAY 1.021277 (-6825 4650);
PAINT AQUA (-6825 4650);
DISPLAY INVISIBLE (-6825 4650);
FORCEPROP 0 LAST $SEC 1
J 0
(-6825 4650);
DISPLAY 0.680851 (-6825 4650);
PAINT MONO (-6825 4650);
DISPLAY INVISIBLE (-6825 4650);
FORCEPROP 0 LAST CDS_SEC 1
J 0
(-6825 4650);
DISPLAY 1.021277 (-6825 4650);
DISPLAY INVISIBLE (-6825 4650);
FORCEADD Q_CAP..1
(-6475 4450);
FORCEPROP 1 LAST PART_NUMBER CH6223MEA01
J 0
(-6425 4300);
DISPLAY 0.617021 (-6425 4300);
PAINT BLUE (-6425 4300);
DISPLAY INVISIBLE (-6425 4300);
FORCEPROP 1 LAST TOLERANCE 20%
J 0
(-6425 4450);
DISPLAY 0.617021 (-6425 4450);
PAINT SKYBLUE (-6425 4450);
FORCEPROP 1 LAST VALUE 22UF
J 0
(-6425 4550);
DISPLAY 0.617021 (-6425 4550);
PAINT SKYBLUE (-6425 4550);
FORCEPROP 1 LAST PACK_TYPE C0805
J 0
(-6425 4350);
DISPLAY 0.617021 (-6425 4350);
PAINT SKYBLUE (-6425 4350);
FORCEPROP 1 LAST VOLTAGE 16V
J 0
(-6425 4500);
DISPLAY 0.617021 (-6425 4500);
PAINT SKYBLUE (-6425 4500);
FORCEPROP 1 LAST MATERIAL X6S
J 0
(-6425 4400);
DISPLAY 0.617021 (-6425 4400);
PAINT SKYBLUE (-6425 4400);
FORCEPROP 1 LAST LOCATION PC179
J 0
(-6425 4600);
DISPLAY 0.617021 (-6425 4600);
PAINT AQUA (-6425 4600);
FORCEPROP 1 LASTPIN (-6475 4550) $PN 1
J 0
(-6465 4530);
DISPLAY 0.617021 (-6465 4530);
PAINT MONO (-6465 4530);
FORCEPROP 1 LASTPIN (-6475 4350) $PN 2
J 0
(-6465 4330);
DISPLAY 0.617021 (-6465 4330);
PAINT MONO (-6465 4330);
FORCEPROP 2 LAST CDS_LIB pure_quanta
J 0
(-6475 4450);
DISPLAY INVISIBLE (-6475 4450);
FORCEPROP 1 LAST PATH I26
J 0
(-6425 4600);
DISPLAY 0.978723 (-6425 4600);
PAINT WHITE (-6425 4600);
DISPLAY INVISIBLE (-6425 4600);
FORCEPROP 1 LAST LOCATION PC179
J 0
(-6425 4650);
DISPLAY 1.021277 (-6425 4650);
PAINT AQUA (-6425 4650);
DISPLAY INVISIBLE (-6425 4650);
FORCEPROP 0 LAST $SEC 1
J 0
(-6425 4650);
DISPLAY 0.680851 (-6425 4650);
PAINT MONO (-6425 4650);
DISPLAY INVISIBLE (-6425 4650);
FORCEPROP 0 LAST CDS_SEC 1
J 0
(-6425 4650);
DISPLAY 1.021277 (-6425 4650);
DISPLAY INVISIBLE (-6425 4650);
FORCEADD Q_CAP..1
(-6075 4450);
FORCEPROP 1 LAST PART_NUMBER CH6223MEA01
J 0
(-6025 4300);
DISPLAY 0.617021 (-6025 4300);
PAINT BLUE (-6025 4300);
DISPLAY INVISIBLE (-6025 4300);
FORCEPROP 1 LAST TOLERANCE 20%
J 0
(-6025 4450);
DISPLAY 0.617021 (-6025 4450);
PAINT SKYBLUE (-6025 4450);
FORCEPROP 1 LAST VALUE 22UF
J 0
(-6025 4550);
DISPLAY 0.617021 (-6025 4550);
PAINT SKYBLUE (-6025 4550);
FORCEPROP 1 LAST PACK_TYPE C0805
J 0
(-6025 4350);
DISPLAY 0.617021 (-6025 4350);
PAINT SKYBLUE (-6025 4350);
FORCEPROP 1 LAST VOLTAGE 16V
J 0
(-6025 4500);
DISPLAY 0.617021 (-6025 4500);
PAINT SKYBLUE (-6025 4500);
FORCEPROP 1 LAST MATERIAL X6S
J 0
(-6025 4400);
DISPLAY 0.617021 (-6025 4400);
PAINT SKYBLUE (-6025 4400);
FORCEPROP 1 LAST LOCATION PC180
J 0
(-6025 4600);
DISPLAY 0.617021 (-6025 4600);
PAINT AQUA (-6025 4600);
FORCEPROP 1 LASTPIN (-6075 4550) $PN 1
J 0
(-6065 4530);
DISPLAY 0.617021 (-6065 4530);
PAINT MONO (-6065 4530);
FORCEPROP 1 LASTPIN (-6075 4350) $PN 2
J 0
(-6065 4330);
DISPLAY 0.617021 (-6065 4330);
PAINT MONO (-6065 4330);
FORCEPROP 2 LAST CDS_LIB pure_quanta
J 0
(-6075 4450);
DISPLAY INVISIBLE (-6075 4450);
FORCEPROP 1 LAST PATH I27
J 0
(-6025 4600);
DISPLAY 0.978723 (-6025 4600);
PAINT WHITE (-6025 4600);
DISPLAY INVISIBLE (-6025 4600);
FORCEPROP 1 LAST LOCATION PC180
J 0
(-6025 4650);
DISPLAY 1.021277 (-6025 4650);
PAINT AQUA (-6025 4650);
DISPLAY INVISIBLE (-6025 4650);
FORCEPROP 0 LAST $SEC 1
J 0
(-6025 4650);
DISPLAY 0.680851 (-6025 4650);
PAINT MONO (-6025 4650);
DISPLAY INVISIBLE (-6025 4650);
FORCEPROP 0 LAST CDS_SEC 1
J 0
(-6025 4650);
DISPLAY 1.021277 (-6025 4650);
DISPLAY INVISIBLE (-6025 4650);
FORCEADD Q_CAP..1
(-5200 3350);
FORCEPROP 1 LAST PART_NUMBER CH4106K1B01
J 0
(-5150 3175);
DISPLAY 0.617021 (-5150 3175);
PAINT BLUE (-5150 3175);
DISPLAY INVISIBLE (-5150 3175);
FORCEPROP 1 LAST VALUE 100NF
J 0
(-5150 3425);
DISPLAY 0.617021 (-5150 3425);
PAINT SKYBLUE (-5150 3425);
FORCEPROP 1 LAST VOLTAGE 50V
J 0
(-5150 3375);
DISPLAY 0.617021 (-5150 3375);
PAINT SKYBLUE (-5150 3375);
FORCEPROP 1 LAST PACK_TYPE C0402
J 0
(-5150 3225);
DISPLAY 0.617021 (-5150 3225);
PAINT SKYBLUE (-5150 3225);
FORCEPROP 1 LAST TOLERANCE 10%
J 0
(-5150 3325);
DISPLAY 0.617021 (-5150 3325);
PAINT SKYBLUE (-5150 3325);
FORCEPROP 1 LAST MATERIAL X7R
J 0
(-5150 3275);
DISPLAY 0.617021 (-5150 3275);
PAINT SKYBLUE (-5150 3275);
FORCEPROP 1 LAST LOCATION PC181
J 0
(-5150 3475);
DISPLAY 0.617021 (-5150 3475);
PAINT AQUA (-5150 3475);
FORCEPROP 1 LASTPIN (-5200 3450) $PN 1
J 0
(-5190 3430);
DISPLAY 0.617021 (-5190 3430);
PAINT MONO (-5190 3430);
FORCEPROP 1 LASTPIN (-5200 3250) $PN 2
J 0
(-5190 3230);
DISPLAY 0.617021 (-5190 3230);
PAINT MONO (-5190 3230);
FORCEPROP 2 LAST CDS_LIB pure_quanta
J 0
(-5200 3350);
DISPLAY INVISIBLE (-5200 3350);
FORCEPROP 1 LAST PATH I28
J 0
(-5150 3500);
DISPLAY 0.978723 (-5150 3500);
PAINT WHITE (-5150 3500);
DISPLAY INVISIBLE (-5150 3500);
FORCEPROP 1 LAST LOCATION PC181
J 0
(-5150 3525);
DISPLAY 1.021277 (-5150 3525);
PAINT AQUA (-5150 3525);
DISPLAY INVISIBLE (-5150 3525);
FORCEPROP 0 LAST $SEC 1
J 0
(-5150 3525);
DISPLAY 0.680851 (-5150 3525);
PAINT MONO (-5150 3525);
DISPLAY INVISIBLE (-5150 3525);
FORCEPROP 0 LAST CDS_SEC 1
J 0
(-5150 3525);
DISPLAY 1.021277 (-5150 3525);
DISPLAY INVISIBLE (-5150 3525);
FORCEADD Q_INDUCTOR..1
(-5400 3575);
FORCEPROP 1 LAST PART_NUMBER CV+30Y0KZ05
J 0
(-5525 3685);
DISPLAY 0.617021 (-5525 3685);
PAINT BLUE (-5525 3685);
DISPLAY INVISIBLE (-5525 3685);
FORCEPROP 1 LAST MATERIAL IND
J 0
(-5525 3630);
DISPLAY 0.617021 (-5525 3630);
PAINT SKYBLUE (-5525 3630);
FORCEPROP 2 LAST VALUE 300NH/33A
J 0
(-5525 3825);
DISPLAY 0.617021 (-5525 3825);
PAINT SKYBLUE (-5525 3825);
FORCEPROP 2 LAST PACK_TYPE SMLF
J 0
(-5525 3775);
DISPLAY 0.617021 (-5525 3775);
PAINT SKYBLUE (-5525 3775);
FORCEPROP 1 LAST LOCATION PL3
J 0
(-5525 3735);
DISPLAY 0.617021 (-5525 3735);
PAINT AQUA (-5525 3735);
FORCEPROP 0 LASTPIN (-5500 3550) $PN 1
J 2
(-5510 3560);
DISPLAY 0.617021 (-5510 3560);
PAINT MONO (-5510 3560);
FORCEPROP 0 LASTPIN (-5300 3550) $PN 2
J 0
(-5290 3560);
DISPLAY 0.617021 (-5290 3560);
PAINT MONO (-5290 3560);
FORCEPROP 1 LAST NEEDS_NO_SIZE TRUE
J 0
(-5400 3575);
DISPLAY 0.468085 (-5400 3575);
PAINT GREEN (-5400 3575);
DISPLAY INVISIBLE (-5400 3575);
FORCEPROP 2 LAST CDS_LIB pure_quanta
J 0
(-5400 3575);
DISPLAY INVISIBLE (-5400 3575);
FORCEPROP 1 LAST PATH I29
J 0
(-5325 3630);
DISPLAY 0.723404 (-5325 3630);
PAINT GREEN (-5325 3630);
DISPLAY INVISIBLE (-5325 3630);
FORCEPROP 0 LAST $SEC 1
J 0
(-5525 3875);
DISPLAY 0.680851 (-5525 3875);
PAINT MONO (-5525 3875);
DISPLAY INVISIBLE (-5525 3875);
FORCEPROP 0 LAST CDS_SEC 1
J 0
(-5525 3875);
DISPLAY 1.021277 (-5525 3875);
DISPLAY INVISIBLE (-5525 3875);
FORCEADD OFFPAGE..1
(-9525 2950);
FORCEPROP 2 LAST $XR0 274 
J 0
(-9777 2950);
DISPLAY 0.638298 (-9777 2950);
PAINT MONO (-9777 2950);
FORCEPROP 1 LAST COMMENT_BODY TRUE
J 0
(-9400 2850);
DISPLAY 0.872340 (-9400 2850);
PAINT GREEN (-9400 2850);
DISPLAY INVISIBLE (-9400 2850);
FORCEPROP 1 LAST OFFPAGE TRUE
J 0
(-9200 2825);
DISPLAY 0.872340 (-9200 2825);
PAINT GREEN (-9200 2825);
DISPLAY INVISIBLE (-9200 2825);
FORCEPROP 2 LAST CDS_LIB standard
J 0
(-9525 2950);
DISPLAY INVISIBLE (-9525 2950);
FORCEPROP 2 LAST PATH I3
J 0
(-9775 3000);
DISPLAY 1.021277 (-9775 3000);
DISPLAY INVISIBLE (-9775 3000);
FORCEADD UNIVERSAL_GND..1
(-5475 4025);
FORCEPROP 3 LASTPIN (-5475 4075) SIG_NAME GND\g
J 0
(-5465 4085);
DISPLAY 0.659574 (-5465 4085);
PAINT MONO (-5465 4085);
DISPLAY INVISIBLE (-5465 4085);
FORCEPROP 1 LAST HDL_POWER GND
J 1
(-5450 3950);
DISPLAY 0.872340 (-5450 3950);
PAINT GREEN (-5450 3950);
DISPLAY INVISIBLE (-5450 3950);
FORCEPROP 2 LAST CDS_LIB logical_power
J 0
(-5475 4025);
PAINT MONO (-5475 4025);
DISPLAY INVISIBLE (-5475 4025);
FORCEPROP 1 LAST PATH I30
J 0
(-5400 4025);
DISPLAY 0.872340 (-5400 4025);
PAINT AQUA (-5400 4025);
DISPLAY INVISIBLE (-5400 4025);
FORCEADD Q_CAP..1
(-4800 3350);
FORCEPROP 1 LAST PART_NUMBER CH622KMEA03
J 0
(-4750 3175);
DISPLAY 0.617021 (-4750 3175);
PAINT BLUE (-4750 3175);
DISPLAY INVISIBLE (-4750 3175);
FORCEPROP 1 LAST TOLERANCE 20%
J 0
(-4750 3325);
DISPLAY 0.617021 (-4750 3325);
PAINT SKYBLUE (-4750 3325);
FORCEPROP 1 LAST VOLTAGE 4V
J 0
(-4750 3375);
DISPLAY 0.617021 (-4750 3375);
PAINT SKYBLUE (-4750 3375);
FORCEPROP 1 LAST PACK_TYPE C0805
J 0
(-4750 3225);
DISPLAY 0.617021 (-4750 3225);
PAINT SKYBLUE (-4750 3225);
FORCEPROP 1 LAST MATERIAL X6S
J 0
(-4750 3275);
DISPLAY 0.617021 (-4750 3275);
PAINT SKYBLUE (-4750 3275);
FORCEPROP 1 LAST VALUE 22UF
J 0
(-4750 3425);
DISPLAY 0.617021 (-4750 3425);
PAINT SKYBLUE (-4750 3425);
FORCEPROP 1 LAST LOCATION PC184
J 0
(-4750 3475);
DISPLAY 0.617021 (-4750 3475);
PAINT AQUA (-4750 3475);
FORCEPROP 1 LASTPIN (-4800 3450) $PN 1
J 0
(-4790 3430);
DISPLAY 0.617021 (-4790 3430);
PAINT MONO (-4790 3430);
FORCEPROP 1 LASTPIN (-4800 3250) $PN 2
J 0
(-4790 3230);
DISPLAY 0.617021 (-4790 3230);
PAINT MONO (-4790 3230);
FORCEPROP 2 LAST CDS_LIB pure_quanta
J 0
(-4800 3350);
DISPLAY INVISIBLE (-4800 3350);
FORCEPROP 1 LAST PATH I31
J 0
(-4750 3500);
DISPLAY 0.978723 (-4750 3500);
PAINT WHITE (-4750 3500);
DISPLAY INVISIBLE (-4750 3500);
FORCEPROP 1 LAST LOCATION PC184
J 0
(-4750 3525);
DISPLAY 1.021277 (-4750 3525);
PAINT AQUA (-4750 3525);
DISPLAY INVISIBLE (-4750 3525);
FORCEPROP 0 LAST $SEC 1
J 0
(-4750 3525);
DISPLAY 0.680851 (-4750 3525);
PAINT MONO (-4750 3525);
DISPLAY INVISIBLE (-4750 3525);
FORCEPROP 0 LAST CDS_SEC 1
J 0
(-4750 3525);
DISPLAY 1.021277 (-4750 3525);
DISPLAY INVISIBLE (-4750 3525);
FORCEADD Q_CAP..1
(-4375 3350);
FORCEPROP 1 LAST PART_NUMBER CH622KMEA03
J 0
(-4325 3175);
DISPLAY 0.617021 (-4325 3175);
PAINT BLUE (-4325 3175);
DISPLAY INVISIBLE (-4325 3175);
FORCEPROP 1 LAST TOLERANCE 20%
J 0
(-4325 3325);
DISPLAY 0.617021 (-4325 3325);
PAINT SKYBLUE (-4325 3325);
FORCEPROP 1 LAST VOLTAGE 4V
J 0
(-4325 3375);
DISPLAY 0.617021 (-4325 3375);
PAINT SKYBLUE (-4325 3375);
FORCEPROP 1 LAST VALUE 22UF
J 0
(-4325 3425);
DISPLAY 0.617021 (-4325 3425);
PAINT SKYBLUE (-4325 3425);
FORCEPROP 1 LAST PACK_TYPE C0805
J 0
(-4325 3225);
DISPLAY 0.617021 (-4325 3225);
PAINT SKYBLUE (-4325 3225);
FORCEPROP 1 LAST MATERIAL X6S
J 0
(-4325 3275);
DISPLAY 0.617021 (-4325 3275);
PAINT SKYBLUE (-4325 3275);
FORCEPROP 1 LAST LOCATION PC186
J 0
(-4325 3475);
DISPLAY 0.617021 (-4325 3475);
PAINT AQUA (-4325 3475);
FORCEPROP 1 LASTPIN (-4375 3450) $PN 1
J 0
(-4365 3430);
DISPLAY 0.617021 (-4365 3430);
PAINT MONO (-4365 3430);
FORCEPROP 1 LASTPIN (-4375 3250) $PN 2
J 0
(-4365 3230);
DISPLAY 0.617021 (-4365 3230);
PAINT MONO (-4365 3230);
FORCEPROP 2 LAST CDS_LIB pure_quanta
J 0
(-4375 3350);
DISPLAY INVISIBLE (-4375 3350);
FORCEPROP 1 LAST PATH I32
J 0
(-4325 3500);
DISPLAY 0.978723 (-4325 3500);
PAINT WHITE (-4325 3500);
DISPLAY INVISIBLE (-4325 3500);
FORCEPROP 1 LAST LOCATION PC186
J 0
(-4325 3525);
DISPLAY 1.021277 (-4325 3525);
PAINT AQUA (-4325 3525);
DISPLAY INVISIBLE (-4325 3525);
FORCEPROP 0 LAST $SEC 1
J 0
(-4325 3525);
DISPLAY 0.680851 (-4325 3525);
PAINT MONO (-4325 3525);
DISPLAY INVISIBLE (-4325 3525);
FORCEPROP 0 LAST CDS_SEC 1
J 0
(-4325 3525);
DISPLAY 1.021277 (-4325 3525);
DISPLAY INVISIBLE (-4325 3525);
FORCEADD Q_CAPP..1
(-3925 3350);
FORCEPROP 1 LAST PART_NUMBER CC7560JMD16
J 0
(-3875 3175);
DISPLAY 0.617021 (-3875 3175);
PAINT BLUE (-3875 3175);
DISPLAY INVISIBLE (-3875 3175);
FORCEPROP 1 LAST PACK_TYPE THLF
J 0
(-3875 3225);
DISPLAY 0.617021 (-3875 3225);
PAINT SKYBLUE (-3875 3225);
FORCEPROP 1 LAST VALUE 560UF
J 0
(-3875 3425);
DISPLAY 0.617021 (-3875 3425);
PAINT SKYBLUE (-3875 3425);
FORCEPROP 1 LAST TOLERANCE 20%
J 0
(-3875 3375);
DISPLAY 0.617021 (-3875 3375);
PAINT SKYBLUE (-3875 3375);
FORCEPROP 1 LAST MATERIAL OSCON
J 0
(-3875 3275);
DISPLAY 0.617021 (-3875 3275);
PAINT SKYBLUE (-3875 3275);
FORCEPROP 1 LAST VOLTAGE 2.5V
J 0
(-3875 3325);
DISPLAY 0.617021 (-3875 3325);
PAINT SKYBLUE (-3875 3325);
FORCEPROP 1 LAST LOCATION PC2180
J 0
(-3875 3475);
DISPLAY 0.617021 (-3875 3475);
PAINT AQUA (-3875 3475);
FORCEPROP 1 LASTPIN (-3925 3450) $PN 1
J 0
(-3915 3435);
DISPLAY 0.617021 (-3915 3435);
PAINT MONO (-3915 3435);
FORCEPROP 1 LASTPIN (-3925 3250) $PN 2
J 0
(-3915 3235);
DISPLAY 0.617021 (-3915 3235);
PAINT MONO (-3915 3235);
FORCEPROP 2 LAST CDS_LIB pure_quanta
J 0
(-3925 3350);
DISPLAY INVISIBLE (-3925 3350);
FORCEPROP 1 LAST PATH I33
J 0
(-3875 3500);
DISPLAY 0.978723 (-3875 3500);
DISPLAY INVISIBLE (-3875 3500);
FORCEPROP 2 LAST $SEC 1
J 0
(-3875 3550);
DISPLAY 0.680851 (-3875 3550);
PAINT MONO (-3875 3550);
DISPLAY INVISIBLE (-3875 3550);
FORCEPROP 2 LAST CDS_SEC 1
J 0
(-3875 3550);
DISPLAY 1.021277 (-3875 3550);
DISPLAY INVISIBLE (-3875 3550);
FORCEADD Q_CAPP..1
(-3525 3350);
FORCEPROP 1 LAST PART_NUMBER CH733LY8802
J 0
(-3475 3175);
DISPLAY 0.617021 (-3475 3175);
PAINT BLUE (-3475 3175);
DISPLAY INVISIBLE (-3475 3175);
FORCEPROP 1 LAST VOLTAGE 2.5V
J 0
(-3475 3325);
DISPLAY 0.617021 (-3475 3325);
PAINT SKYBLUE (-3475 3325);
FORCEPROP 1 LAST TOLERANCE +10/-35%
J 0
(-3475 3375);
DISPLAY 0.617021 (-3475 3375);
PAINT SKYBLUE (-3475 3375);
FORCEPROP 1 LAST MATERIAL SPCAP
J 0
(-3475 3275);
DISPLAY 0.617021 (-3475 3275);
PAINT SKYBLUE (-3475 3275);
FORCEPROP 1 LAST PACK_TYPE SMLF
J 0
(-3475 3225);
DISPLAY 0.617021 (-3475 3225);
PAINT SKYBLUE (-3475 3225);
FORCEPROP 1 LAST VALUE 330UF
J 0
(-3475 3425);
DISPLAY 0.617021 (-3475 3425);
PAINT SKYBLUE (-3475 3425);
FORCEPROP 1 LAST LOCATION PC1900
J 0
(-3475 3475);
DISPLAY 0.617021 (-3475 3475);
PAINT AQUA (-3475 3475);
FORCEPROP 1 LASTPIN (-3525 3450) $PN 1
J 0
(-3515 3435);
DISPLAY 0.617021 (-3515 3435);
FORCEPROP 1 LASTPIN (-3525 3250) $PN 2
J 0
(-3515 3235);
DISPLAY 0.617021 (-3515 3235);
FORCEPROP 2 LAST CDS_LIB pure_quanta
J 0
(-3525 3350);
PAINT MONO (-3525 3350);
DISPLAY INVISIBLE (-3525 3350);
FORCEPROP 1 LAST PATH I34
J 0
(-3475 3500);
DISPLAY 0.978723 (-3475 3500);
DISPLAY INVISIBLE (-3475 3500);
FORCEPROP 2 LAST $SEC 1
J 0
(-3475 3550);
DISPLAY 0.680851 (-3475 3550);
PAINT MONO (-3475 3550);
DISPLAY INVISIBLE (-3475 3550);
FORCEPROP 2 LAST CDS_SEC 1
J 0
(-3475 3550);
DISPLAY 1.021277 (-3475 3550);
DISPLAY INVISIBLE (-3475 3550);
FORCEADD UNIVERSAL_GND..1
(-3050 2950);
FORCEPROP 3 LASTPIN (-3050 3000) SIG_NAME GND\g
J 0
(-3040 3010);
DISPLAY 0.659574 (-3040 3010);
PAINT MONO (-3040 3010);
DISPLAY INVISIBLE (-3040 3010);
FORCEPROP 1 LAST HDL_POWER GND
J 1
(-3025 2875);
DISPLAY 0.872340 (-3025 2875);
PAINT GREEN (-3025 2875);
DISPLAY INVISIBLE (-3025 2875);
FORCEPROP 2 LAST CDS_LIB logical_power
J 0
(-3050 2950);
PAINT MONO (-3050 2950);
DISPLAY INVISIBLE (-3050 2950);
FORCEPROP 1 LAST PATH I35
J 0
(-2975 2950);
DISPLAY 0.872340 (-2975 2950);
PAINT AQUA (-2975 2950);
DISPLAY INVISIBLE (-2975 2950);
FORCEADD Q_RES..2
(-3050 3350);
FORCEPROP 1 LAST PART_NUMBER CS14992FB06
J 0
(-3010 3225);
DISPLAY 0.617021 (-3010 3225);
PAINT BLUE (-3010 3225);
DISPLAY INVISIBLE (-3010 3225);
FORCEPROP 1 LAST WATTAGE 1/16W
J 0
(-3010 3325);
DISPLAY 0.617021 (-3010 3325);
PAINT SKYBLUE (-3010 3325);
FORCEPROP 1 LAST VALUE 499
J 0
(-3005 3425);
DISPLAY 0.617021 (-3005 3425);
PAINT SKYBLUE (-3005 3425);
FORCEPROP 1 LAST TOLERANCE 1%
J 0
(-3005 3375);
DISPLAY 0.617021 (-3005 3375);
PAINT SKYBLUE (-3005 3375);
FORCEPROP 1 LAST MATERIAL CHIP
J 0
(-3010 3275);
DISPLAY 0.617021 (-3010 3275);
PAINT SKYBLUE (-3010 3275);
FORCEPROP 1 LAST PACK_TYPE 0402LF
J 0
(-3010 3175);
DISPLAY 0.617021 (-3010 3175);
PAINT SKYBLUE (-3010 3175);
FORCEPROP 1 LAST LOCATION PR4229
J 0
(-3005 3475);
DISPLAY 0.617021 (-3005 3475);
PAINT AQUA (-3005 3475);
FORCEPROP 1 LASTPIN (-3050 3450) $PN 1
J 0
(-3045 3412);
DISPLAY 0.787234 (-3045 3412);
PAINT MONO (-3045 3412);
FORCEPROP 1 LASTPIN (-3050 3250) $PN 2
J 0
(-3045 3260);
DISPLAY 0.787234 (-3045 3260);
PAINT MONO (-3045 3260);
FORCEPROP 2 LAST BOM_COST VR_PCH
J 0
(-3000 3525);
DISPLAY 0.680851 (-3000 3525);
DISPLAY INVISIBLE (-3000 3525);
FORCEPROP 2 LAST CDS_LIB pure_quanta
J 0
(-3050 3350);
DISPLAY INVISIBLE (-3050 3350);
FORCEPROP 1 LAST PATH I36
J 0
(-3000 3525);
DISPLAY 0.978723 (-3000 3525);
PAINT WHITE (-3000 3525);
DISPLAY INVISIBLE (-3000 3525);
FORCEPROP 0 LAST $SEC 1
J 0
(-3000 3525);
DISPLAY 0.680851 (-3000 3525);
PAINT MONO (-3000 3525);
DISPLAY INVISIBLE (-3000 3525);
FORCEPROP 0 LAST CDS_SEC 1
J 0
(-3000 3525);
DISPLAY 1.021277 (-3000 3525);
DISPLAY INVISIBLE (-3000 3525);
FORCEADD VCC15..1
(-3050 3700);
FORCEPROP 3 LASTPIN (-3050 3650) SIG_NAME PVCCFA_EHV_CPU0\g
J 0
(-3040 3660);
DISPLAY 0.659574 (-3040 3660);
PAINT MONO (-3040 3660);
DISPLAY INVISIBLE (-3040 3660);
FORCEPROP 1 LAST HDL_POWER PVCCFA_EHV_CPU0
J 1
(-3050 3750);
DISPLAY 0.617021 (-3050 3750);
PAINT GREEN (-3050 3750);
FORCEPROP 2 LAST CDS_LIB logical_power
J 0
(-3050 3700);
DISPLAY INVISIBLE (-3050 3700);
FORCEPROP 1 LAST PATH I37
J 0
(-3000 3725);
DISPLAY 0.872340 (-3000 3725);
PAINT AQUA (-3000 3725);
DISPLAY INVISIBLE (-3000 3725);
FORCEADD VCC15..1
(-5475 4825);
FORCEPROP 3 LASTPIN (-5475 4775) SIG_NAME SW_P12V_PVCCINFAON_CPU0_FLT\g
J 0
(-5465 4785);
DISPLAY 0.659574 (-5465 4785);
PAINT MONO (-5465 4785);
DISPLAY INVISIBLE (-5465 4785);
FORCEPROP 1 LAST HDL_POWER SW_P12V_PVCCINFAON_CPU0_FLT
J 1
(-5425 4875);
DISPLAY 0.617021 (-5425 4875);
PAINT GREEN (-5425 4875);
FORCEPROP 2 LAST CDS_LIB logical_power
J 0
(-5475 4825);
DISPLAY INVISIBLE (-5475 4825);
FORCEPROP 1 LAST PATH I38
J 0
(-5425 4850);
DISPLAY 0.872340 (-5425 4850);
PAINT AQUA (-5425 4850);
DISPLAY INVISIBLE (-5425 4850);
FORCEADD OFFPAGE..5
(-9525 3050);
FORCEPROP 2 LAST $XR0 274 
J 0
(-9810 3050);
DISPLAY 0.638298 (-9810 3050);
PAINT MONO (-9810 3050);
FORCEPROP 1 LAST COMMENT_BODY TRUE
J 0
(-9425 2975);
DISPLAY 0.872340 (-9425 2975);
PAINT GREEN (-9425 2975);
DISPLAY INVISIBLE (-9425 2975);
FORCEPROP 1 LAST OFFPAGE TRUE
J 0
(-9200 2925);
DISPLAY 0.872340 (-9200 2925);
PAINT GREEN (-9200 2925);
DISPLAY INVISIBLE (-9200 2925);
FORCEPROP 2 LAST CDS_LIB standard
J 0
(-9525 3050);
DISPLAY INVISIBLE (-9525 3050);
FORCEPROP 2 LAST PATH I4
J 0
(-9800 3100);
DISPLAY 1.021277 (-9800 3100);
DISPLAY INVISIBLE (-9800 3100);
FORCEADD UNIVERSAL_GND..1
(-10525 3275);
FORCEPROP 3 LASTPIN (-10525 3325) SIG_NAME GND\g
J 0
(-10515 3335);
DISPLAY 0.659574 (-10515 3335);
PAINT MONO (-10515 3335);
DISPLAY INVISIBLE (-10515 3335);
FORCEPROP 1 LAST HDL_POWER GND
J 1
(-10500 3200);
DISPLAY 0.872340 (-10500 3200);
PAINT GREEN (-10500 3200);
DISPLAY INVISIBLE (-10500 3200);
FORCEPROP 2 LAST CDS_LIB logical_power
J 0
(-10525 3275);
PAINT MONO (-10525 3275);
DISPLAY INVISIBLE (-10525 3275);
FORCEPROP 1 LAST PATH I5
J 0
(-10450 3275);
DISPLAY 0.872340 (-10450 3275);
PAINT AQUA (-10450 3275);
DISPLAY INVISIBLE (-10450 3275);
FORCEADD OFFPAGE..1
(-9525 3450);
FORCEPROP 2 LAST $XR1 275 
J 0
(-9897 3450);
DISPLAY 0.638298 (-9897 3450);
PAINT MONO (-9897 3450);
FORCEPROP 2 LAST $XR0 274 
J 0
(-9777 3450);
DISPLAY 0.638298 (-9777 3450);
PAINT MONO (-9777 3450);
FORCEPROP 1 LAST COMMENT_BODY TRUE
J 0
(-9400 3350);
DISPLAY 0.872340 (-9400 3350);
PAINT GREEN (-9400 3350);
DISPLAY INVISIBLE (-9400 3350);
FORCEPROP 1 LAST OFFPAGE TRUE
J 0
(-9200 3325);
DISPLAY 0.872340 (-9200 3325);
PAINT GREEN (-9200 3325);
DISPLAY INVISIBLE (-9200 3325);
FORCEPROP 2 LAST CDS_LIB standard
J 0
(-9525 3450);
DISPLAY INVISIBLE (-9525 3450);
FORCEPROP 2 LAST PATH I6
J 0
(-9775 3500);
DISPLAY 1.021277 (-9775 3500);
DISPLAY INVISIBLE (-9775 3500);
FORCEADD OFFPAGE..5
(-9525 3550);
FORCEPROP 2 LAST $XR0 274 
J 0
(-9810 3550);
DISPLAY 0.638298 (-9810 3550);
PAINT MONO (-9810 3550);
FORCEPROP 1 LAST COMMENT_BODY TRUE
J 0
(-9425 3475);
DISPLAY 0.872340 (-9425 3475);
PAINT GREEN (-9425 3475);
DISPLAY INVISIBLE (-9425 3475);
FORCEPROP 1 LAST OFFPAGE TRUE
J 0
(-9200 3425);
DISPLAY 0.872340 (-9200 3425);
PAINT GREEN (-9200 3425);
DISPLAY INVISIBLE (-9200 3425);
FORCEPROP 2 LAST CDS_LIB standard
J 0
(-9525 3550);
DISPLAY INVISIBLE (-9525 3550);
FORCEPROP 2 LAST PATH I7
J 0
(-9800 3600);
DISPLAY 1.021277 (-9800 3600);
DISPLAY INVISIBLE (-9800 3600);
FORCEADD Q_RES..2
(-10075 5025);
FORCEPROP 1 LAST PART_NUMBER CS00002JB13
J 0
(-10035 4900);
DISPLAY 0.617021 (-10035 4900);
PAINT BLUE (-10035 4900);
DISPLAY INVISIBLE (-10035 4900);
FORCEPROP 1 LAST MATERIAL CHIP
J 0
(-10035 4950);
DISPLAY 0.617021 (-10035 4950);
PAINT SKYBLUE (-10035 4950);
FORCEPROP 1 LAST PACK_TYPE 0402LF
J 0
(-10035 4850);
DISPLAY 0.617021 (-10035 4850);
PAINT SKYBLUE (-10035 4850);
FORCEPROP 1 LAST VALUE 0
J 0
(-10030 5100);
DISPLAY 0.617021 (-10030 5100);
PAINT SKYBLUE (-10030 5100);
FORCEPROP 1 LAST TOLERANCE 5%
J 0
(-10030 5050);
DISPLAY 0.617021 (-10030 5050);
PAINT SKYBLUE (-10030 5050);
FORCEPROP 1 LAST WATTAGE 1/16W
J 0
(-10035 5000);
DISPLAY 0.617021 (-10035 5000);
PAINT SKYBLUE (-10035 5000);
FORCEPROP 1 LAST LOCATION PR442
J 0
(-10030 5150);
DISPLAY 0.617021 (-10030 5150);
PAINT AQUA (-10030 5150);
FORCEPROP 2 LAST CDS_LIB pure_quanta
J 0
(-10075 5025);
DISPLAY INVISIBLE (-10075 5025);
FORCEPROP 1 LAST PATH I8
J 0
(-10025 5200);
DISPLAY 0.978723 (-10025 5200);
PAINT WHITE (-10025 5200);
DISPLAY INVISIBLE (-10025 5200);
FORCEPROP 0 LAST $SEC 1
J 0
(-10025 5200);
DISPLAY INVISIBLE (-10025 5200);
FORCEPROP 0 LAST CDS_SEC 1
J 0
(-10025 5200);
DISPLAY INVISIBLE (-10025 5200);
FORCEPROP 1 LASTPIN (-10075 5125) $PN 1
J 0
(-10070 5087);
DISPLAY 0.787234 (-10070 5087);
PAINT MONO (-10070 5087);
DISPLAY INVISIBLE (-10070 5087);
FORCEPROP 1 LASTPIN (-10075 4925) $PN 2
J 0
(-10070 4935);
DISPLAY 0.787234 (-10070 4935);
PAINT MONO (-10070 4935);
DISPLAY INVISIBLE (-10070 4935);
FORCEADD VCC15..1
(-10075 5250);
FORCEPROP 3 LASTPIN (-10075 5200) SIG_NAME P5V\g
J 0
(-10065 5210);
DISPLAY 0.659574 (-10065 5210);
PAINT MONO (-10065 5210);
DISPLAY INVISIBLE (-10065 5210);
FORCEPROP 1 LAST HDL_POWER P5V
J 1
(-10075 5300);
DISPLAY 0.617021 (-10075 5300);
PAINT GREEN (-10075 5300);
FORCEPROP 2 LAST CDS_LIB logical_power
J 0
(-10075 5250);
DISPLAY INVISIBLE (-10075 5250);
FORCEPROP 1 LAST PATH I9
J 0
(-10025 5275);
DISPLAY 0.872340 (-10025 5275);
PAINT AQUA (-10025 5275);
DISPLAY INVISIBLE (-10025 5275);
FORCEADD QUANTA_TITLE_BLOCK_C..1
(-2225 350);
FORCEPROP 0 LAST CDS_CON_LAST_MODIFIED Fri Aug 25 14:04:47 2023
J 0
(-4110 365);
DISPLAY INVISIBLE (-4110 365);
FORCEPROP 1 LAST CUSTOM_TXT_CDS <CON_LAST_MODIFIED>
J 0
(-4110 365);
DISPLAY 0.978723 (-4110 365);
FORCEPROP 2 LAST CUSTOM_TXT_CDS <XR_PAGE_TITLE>
J 0
(-10115 5600);
DISPLAY 0.638298 (-10115 5600);
PAINT PINK (-10115 5600);
DISPLAY INVISIBLE (-10115 5600);
FORCEPROP 1 LAST CUSTOM_TXT_CDS <NAME_2>
J 0
(-5400 400);
FORCEPROP 1 LAST CUSTOM_TXT_CDS <NAME_1>
J 0
(-5400 525);
FORCEPROP 1 LAST CUSTOM_TXT_CDS <Q_NUMBER>
J 0
(-3628 453);
DISPLAY 1.212766 (-3628 453);
FORCEPROP 1 LAST CUSTOM_TXT_CDS <Q_PROJ>
J 0
(-4607 452);
DISPLAY 1.212766 (-4607 452);
FORCEPROP 1 LAST CUSTOM_TXT_CDS <Q_REV>
J 0
(-2409 453);
DISPLAY 1.212766 (-2409 453);
FORCEPROP 1 LAST CUSTOM_TXT_CDS <CON_PAGE_NUM> OF <CON_TOTAL_PAGES>
J 0
(-2671 368);
DISPLAY 0.978723 (-2671 368);
FORCEPROP 1 LAST Q_TITLE VCCFA_EHV CPU0 VR PHASE (3/3)
J 0
(-11500 400);
DISPLAY 2.446809 (-11500 400);
PAINT GREEN (-11500 400);
FORCEPROP 1 LAST Q_DEPT 
J 1
(-5988 399);
DISPLAY 1.957447 (-5988 399);
PAINT GREEN (-5988 399);
FORCEPROP 2 LAST CDS_XR_PAGE_TITLE CR-276 : @S9S_MB_2U_LIB.S9S_MB_2U(SCH_1):PAGE276
J 0
(-10115 5600);
DISPLAY 0.638298 (-10115 5600);
PAINT PINK (-10115 5600);
DISPLAY INVISIBLE (-10115 5600);
FORCEPROP 1 LAST CDS_LMAN_SYM_OUTLINE -9475,6775,100,-125
J 0
(-2225 350);
DISPLAY 0.468085 (-2225 350);
PAINT GREEN (-2225 350);
DISPLAY INVISIBLE (-2225 350);
FORCEPROP 2 LAST CDS_LIB pure_quanta
J 0
(-2225 350);
DISPLAY INVISIBLE (-2225 350);
FORCEPROP 2 LAST PAGE_BORDER TRUE
J 0
(-10115 5600);
DISPLAY 0.638298 (-10115 5600);
PAINT PINK (-10115 5600);
DISPLAY INVISIBLE (-10115 5600);
FORCEPROP 1 LAST COMMENT_BODY TRUE
J 0
(-2213 337);
DISPLAY 0.978723 (-2213 337);
PAINT GREEN (-2213 337);
DISPLAY INVISIBLE (-2213 337);
FORCEADD DNS..1
(-10275 2950);
PAINT RED (-10275 2950);
FORCEPROP 1 LAST COMMENT_BODY TRUE
R 1
J 0
(-10200 2725);
DISPLAY 0.872340 (-10200 2725);
PAINT GREEN (-10200 2725);
DISPLAY INVISIBLE (-10200 2725);
FORCEPROP 2 LAST CDS_LIB mstr_misc
J 0
(-10275 2950);
DISPLAY INVISIBLE (-10275 2950);
FORCEADD DNS..1
(-9050 3975);
PAINT RED (-9050 3975);
FORCEPROP 1 LAST COMMENT_BODY TRUE
R 1
J 0
(-8975 3750);
DISPLAY 0.872340 (-8975 3750);
PAINT GREEN (-8975 3750);
DISPLAY INVISIBLE (-8975 3750);
FORCEPROP 2 LAST CDS_LIB mstr_misc
J 0
(-9050 3975);
DISPLAY INVISIBLE (-9050 3975);
FORCEADD DNS..1
(-6675 3025);
PAINT RED (-6675 3025);
FORCEPROP 1 LAST COMMENT_BODY TRUE
R 1
J 0
(-6600 2800);
DISPLAY 0.872340 (-6600 2800);
PAINT GREEN (-6600 2800);
DISPLAY INVISIBLE (-6600 2800);
FORCEPROP 2 LAST CDS_LIB mstr_misc
J 0
(-6675 3025);
DISPLAY INVISIBLE (-6675 3025);
FORCEADD DNS..1
(-9175 5000);
PAINT RED (-9175 5000);
FORCEPROP 1 LAST COMMENT_BODY TRUE
R 1
J 0
(-9100 4775);
DISPLAY 0.872340 (-9100 4775);
PAINT GREEN (-9100 4775);
DISPLAY INVISIBLE (-9100 4775);
FORCEPROP 2 LAST CDS_LIB mstr_misc
J 0
(-9175 5000);
DISPLAY INVISIBLE (-9175 5000);
WIRE 16 -1 (-10075 5200)(-10075 5125);
WIRE 16 -1 (-6100 3350)(-6100 3250);
WIRE 16 -1 (-9225 5200)(-9225 5125);
WIRE 16 -1 (-3050 3650)(-3050 3550);
WIRE 16 -1 (-5475 4775)(-5475 4700);
WIRE 16 -1 (-10275 2875)(-10275 2800);
WIRE 16 -1 (-10525 3350)(-10525 3325);
WIRE 16 -1 (-10525 3350)(-9600 3350);
WIRE 16 -1 (-9600 3900)(-9600 3800);
WIRE 16 -1 (-6100 2950)(-6100 2875);
WIRE 16 -1 (-6100 3000)(-6100 2950);
WIRE 16 -1 (-7675 2950)(-6100 2950);
WIRE 16 -1 (-5475 4075)(-5475 4200);
WIRE 16 -1 (-3050 3000)(-3050 3125);
WIRE 16 -1 (-8525 3050)(-9475 3050);
FORCEPROP 2 LAST SIG_NAME PVCCFA_EHV_CPU0_BTSEN
J 0
(-9235 3060);
DISPLAY 0.617021 (-9235 3060);
WIRE 16 -1 (-3050 3250)(-3050 3125);
WIRE 16 -1 (-3525 3250)(-3525 3125);
WIRE 16 -1 (-3050 3125)(-3525 3125);
WIRE 16 -1 (-3925 3125)(-3925 3250);
WIRE 16 -1 (-3925 3125)(-3525 3125);
WIRE 16 -1 (-4375 3250)(-4375 3125);
WIRE 16 -1 (-4375 3125)(-3925 3125);
WIRE 16 -1 (-4800 3125)(-4800 3250);
WIRE 16 -1 (-4375 3125)(-4800 3125);
WIRE 16 -1 (-4800 3125)(-5200 3125);
WIRE 16 -1 (-5200 3250)(-5200 3125);
WIRE 16 -1 (-3050 3550)(-3050 3450);
WIRE 16 -1 (-3525 3450)(-3525 3550);
WIRE 16 -1 (-3050 3550)(-3525 3550);
WIRE 16 -1 (-3925 3450)(-3925 3550);
WIRE 16 -1 (-3925 3550)(-3525 3550);
WIRE 16 -1 (-4375 3450)(-4375 3550);
WIRE 16 -1 (-4375 3550)(-3925 3550);
WIRE 16 -1 (-4800 3550)(-4800 3450);
WIRE 16 -1 (-4800 3550)(-4375 3550);
WIRE 16 -1 (-5200 3550)(-5300 3550);
WIRE 16 -1 (-5200 3450)(-5200 3550);
WIRE 16 -1 (-5200 3550)(-4800 3550);
WIRE 16 -1 (-6075 4350)(-6075 4200);
WIRE 16 -1 (-5475 4200)(-6075 4200);
WIRE 16 -1 (-6475 4350)(-6475 4200);
WIRE 16 -1 (-6475 4200)(-6075 4200);
WIRE 16 -1 (-6875 4350)(-6875 4200);
WIRE 16 -1 (-6475 4200)(-6875 4200);
WIRE 16 -1 (-7275 4200)(-6875 4200);
WIRE 16 -1 (-7275 4350)(-7275 4200);
WIRE 16 -1 (-6075 4550)(-6075 4700);
WIRE 16 -1 (-5475 4700)(-6075 4700);
WIRE 16 -1 (-6475 4700)(-6475 4550);
WIRE 16 -1 (-6475 4700)(-6075 4700);
WIRE 16 -1 (-6875 4550)(-6875 4700);
WIRE 16 -1 (-6875 4700)(-6475 4700);
WIRE 16 -1 (-7275 4550)(-7275 4700);
WIRE 16 -1 (-7275 4700)(-6875 4700);
WIRE 16 -1 (-7500 4700)(-7275 4700);
WIRE 16 -1 (-7500 4700)(-7500 4200);
WIRE 16 -1 (-7675 4200)(-7500 4200);
WIRE 16 -1 (-7675 3550)(-5500 3550);
FORCEPROP 2 LAST SIG_NAME SW_PVCCFA_EHV_CPU0_SW1
J 0
(-7535 3560);
DISPLAY 0.617021 (-7535 3560);
WIRE 16 -1 (-9075 4200)(-9075 4050);
WIRE 16 -1 (-8525 4200)(-9075 4200);
WIRE 16 -1 (-9600 4200)(-9600 4100);
WIRE 16 -1 (-9075 4200)(-9600 4200);
FORCEPROP 2 LAST SIG_NAME PVCCFA_EHV_CPU0_VDD1
J 0
(-9235 4210);
DISPLAY 0.617021 (-9235 4210);
WIRE 16 -1 (-9600 4300)(-9600 4200);
WIRE 16 -1 (-9225 4925)(-9225 4575);
WIRE 16 -1 (-9600 4575)(-9600 4500);
WIRE 16 -1 (-9600 4575)(-9225 4575);
WIRE 16 -1 (-10075 4575)(-9600 4575);
FORCEPROP 2 LAST SIG_NAME PVCCFA_EHV_CPU0_PVCC
J 0
(-10035 4585);
DISPLAY 0.617021 (-10035 4585);
FORCEPROP 2 LASTPROP $XR1 279 
J 0
(-10311 4585);
DISPLAY 0.638298 (-10311 4585);
PAINT MONO (-10311 4585);
FORCEPROP 2 LASTPROP $XR0 275 
J 0
(-10191 4585);
DISPLAY 0.638298 (-10191 4585);
PAINT MONO (-10191 4585);
WIRE 16 -1 (-10075 4925)(-10075 4575);
WIRE 16 -1 (-6425 3250)(-6100 3250);
WIRE 16 -1 (-5950 4000)(-5950 3925);
WIRE 16 -1 (-6650 4000)(-5950 4000);
FORCEPROP 2 LAST SIG_NAME SW_PVCCFA_EHV_CPU0_BOOT1_R
J 0
(-6410 4010);
DISPLAY 0.617021 (-6410 4010);
WIRE 16 -1 (-6100 3100)(-7675 3100);
WIRE 16 -1 (-6625 3050)(-6100 3050);
WIRE 16 -1 (-6100 3050)(-6100 3100);
WIRE 16 -1 (-6100 3000)(-6100 3050);
WIRE 16 -1 (-7675 3000)(-6100 3000);
WIRE 16 -1 (-7525 4000)(-6850 4000);
FORCEPROP 0 LAST CDS_PHYS_NET_NAME SW_PVCCFA_EHV_CPU0_BOOT1
J 0
(-7485 4029);
PAINT MONO (-7485 4029);
DISPLAY INVISIBLE (-7485 4029);
WIRE 16 -1 (-7525 3900)(-7525 4000);
FORCEPROP 2 LAST SIG_NAME SW_PVCCFA_EHV_CPU0_BOOT1
J 0
(-7710 4010);
DISPLAY 0.617021 (-7710 4010);
WIRE 16 -1 (-7675 3900)(-7525 3900);
WIRE 16 -1 (-7675 3050)(-6825 3050);
FORCEPROP 2 LAST SIG_NAME PVCCFA_EHV_CPU0_FAULT
J 0
(-7535 3060);
DISPLAY 0.617021 (-7535 3060);
WIRE 16 -1 (-7675 3250)(-6625 3250);
FORCEPROP 2 LAST SIG_NAME PVCCFA_EHV_CPU0_NC1
J 0
(-7535 3260);
DISPLAY 0.617021 (-7535 3260);
WIRE 16 -1 (-5950 3650)(-5950 3725);
WIRE 16 -1 (-7675 3650)(-5950 3650);
FORCEPROP 0 LAST CDS_PHYS_NET_NAME SW_PVCCFA_EHV_CPU0_BOOTR1
J 0
(-7485 3690);
PAINT MONO (-7485 3690);
DISPLAY INVISIBLE (-7485 3690);
FORCEPROP 2 LAST SIG_NAME SW_PVCCFA_EHV_CPU0_BOOTR1
J 0
(-7535 3660);
DISPLAY 0.617021 (-7535 3660);
WIRE 16 -1 (-8525 2950)(-9475 2950);
FORCEPROP 2 LAST SIG_NAME PVCCFA_EHV_CPU0_BPWM1
J 0
(-9235 2960);
DISPLAY 0.617021 (-9235 2960);
WIRE 16 -1 (-8525 3550)(-9475 3550);
FORCEPROP 2 LAST SIG_NAME PVCCFA_EHV_CPU0_BCSP1
J 0
(-9235 3560);
DISPLAY 0.617021 (-9235 3560);
WIRE 16 -1 (-8525 3700)(-9075 3700);
FORCEPROP 2 LAST SIG_NAME PVCCFA_EHV_CPU0_NC2
J 0
(-9235 3710);
DISPLAY 0.617021 (-9235 3710);
WIRE 16 -1 (-9075 3850)(-9075 3700);
WIRE 16 -1 (-8750 3350)(-9400 3350);
WIRE 16 -1 (-9475 3450)(-8750 3450);
FORCEPROP 2 LAST SIG_NAME PVCCINFAON_CPU0_VREF
J 0
(-9235 3460);
DISPLAY 0.617021 (-9235 3460);
WIRE 16 -1 (-8750 3450)(-8750 3350);
FORCEPROP 0 LAST CDS_PHYS_NET_NAME PVCCINFAON_CPU0_VREF
J 0
(-8750 3375);
PAINT MONO (-8750 3375);
DISPLAY INVISIBLE (-8750 3375);
WIRE 16 -1 (-8750 3450)(-8525 3450);
WIRE 16 -1 (-10275 3300)(-10275 3075);
WIRE 16 -1 (-8525 3300)(-10275 3300);
FORCEPROP 2 LAST SIG_NAME PVCCFA_EHV_CPU0_LSET1
J 0
(-9235 3310);
DISPLAY 0.617021 (-9235 3310);
DOT 1 (-8750 3450);
DOT 1 (-6100 3000);
DOT 1 (-6100 2950);
DOT 1 (-6100 3050);
DOT 1 (-9600 4200);
DOT 1 (-9600 4575);
DOT 1 (-9075 4200);
DOT 1 (-7275 4700);
DOT 1 (-6875 4200);
DOT 1 (-6875 4700);
DOT 1 (-6475 4200);
DOT 1 (-6075 4200);
DOT 1 (-6475 4700);
DOT 1 (-6075 4700);
DOT 1 (-5200 3550);
DOT 1 (-4800 3125);
DOT 1 (-4800 3550);
DOT 1 (-4375 3125);
DOT 1 (-4375 3550);
DOT 1 (-3925 3125);
DOT 1 (-3525 3125);
DOT 1 (-3925 3550);
DOT 1 (-3525 3550);
DOT 1 (-3050 3125);
DOT 1 (-3050 3550);
FORCENOTE
PVCCFA_EHV_CPU0
(-8475 4825) 0;
DISPLAY LEFT (-8475 4825);
DISPLAY 1.021277 (-8475 4825);
PAINT WHITE (-8475 4825);
FORCENOTE
9.6*6.4*9.0
(-5050 3800) 0;
DISPLAY LEFT (-5050 3800);
DISPLAY 0.808511 (-5050 3800);
FORCENOTE
ISAT = 29A @ 125C
(-5050 3725) 0;
DISPLAY LEFT (-5050 3725);
DISPLAY 0.808511 (-5050 3725);
FORCENOTE
DCR = 0.17M OHM
(-5050 3650) 0;
DISPLAY LEFT (-5050 3650);
DISPLAY 0.808511 (-5050 3650);
FORCENOTE
PG1712.301AHLT
(-5050 3875) 0;
DISPLAY LEFT (-5050 3875);
DISPLAY 0.808511 (-5050 3875);
FORCENOTE
APPLY TO ALL RAILS.
(-4100 2550) 0;
DISPLAY LEFT (-4100 2550);
DISPLAY 1.021277 (-4100 2550);
FORCENOTE
(499OHM) TO ABSORB LEAKAGE FROM SPS.
(-4100 2625) 0;
DISPLAY LEFT (-4100 2625);
DISPLAY 1.021277 (-4100 2625);
FORCENOTE
RENESAS RECOMMEND BLEEDER RESISTOR
(-4100 2700) 0;
DISPLAY LEFT (-4100 2700);
DISPLAY 1.021277 (-4100 2700);
QUIT
